(kicad_pcb
	(version 20260206)
	(generator "pcbnew")
	(generator_version "10.0")
	(general
		(thickness 1.6)
		(legacy_teardrops no)
	)
	(paper "A4")
	(title_block
		(title "Bryce Canyon_R.DPB_16317-1_OCP.brd")
		(comment 1 "Bryce Canyon / footprints 1073-1080 of 2099")
	)
	(layers
		(0 "F.Cu" signal "TOP")
		(4 "In1.Cu" signal "L2GND")
		(6 "In2.Cu" signal "L3")
		(8 "In3.Cu" signal "L4VCC")
		(10 "In4.Cu" signal "L5VCC")
		(12 "In5.Cu" signal "L6")
		(14 "In6.Cu" signal "L7GND")
		(2 "B.Cu" signal "BOTTOM")
		(9 "F.Adhes" user "F.Adhesive")
		(11 "B.Adhes" user "B.Adhesive")
		(13 "F.Paste" user "Package Geometry/Pastemask Top")
		(15 "B.Paste" user "Package Geometry/Pastemask Bottom")
		(5 "F.SilkS" user "Ref Des/Silkscreen Top")
		(7 "B.SilkS" user "Ref Des/Silkscreen Bottom")
		(1 "F.Mask" user "Board Geometry/Soldermask Top")
		(3 "B.Mask" user "Board Geometry/Soldermask Bottom")
		(17 "Dwgs.User" user "User.Drawings")
		(19 "Cmts.User" user "User.Comments")
		(21 "Eco1.User" user "User.Eco1")
		(23 "Eco2.User" user "User.Eco2")
		(25 "Edge.Cuts" user "Board Geometry/Outline")
		(27 "Margin" user)
		(31 "F.CrtYd" user "Package Geometry/Place Bound Top")
		(29 "B.CrtYd" user "Package Geometry/Place Bound Bottom")
		(35 "F.Fab" user "Ref Des/Assembly Top")
		(33 "B.Fab" user "Ref Des/Assembly Bottom")
	)
	(footprint ""
		(layer "F.Cu")
		(at 209.423 -207.01 90)
		(property "Reference" "R50"
			(at 0 0 90)
			(layer "F.SilkS")
			(hide yes)
			(effects
				(font
					(size 1.27 1.27)
				)
			)
		)
		(property "Value" "4K7R2F-GP"
			(at 0.064008 -3.993896 90)
			(unlocked yes)
			(layer "F.Fab")
			(hide yes)
			(effects
				(font
					(size 1.016 1.016)
					(thickness 0.1524)
				)
			)
		)
		(property "Device Type" "R402H16"
			(at 0.064008 -5.517896 90)
			(unlocked yes)
			(layer "F.Fab")
			(hide yes)
			(effects
				(font
					(size 1.016 1.016)
					(thickness 0.1524)
				)
			)
		)
		(duplicate_pad_numbers_are_jumpers no)
		(fp_line
			(start 0.508 -0.9398)
			(end -0.508 -0.9398)
			(stroke
				(width 0.1524)
				(type default)
			)
			(layer "F.SilkS")
		)
		(fp_line
			(start -0.508 -0.9398)
			(end -0.508 0.9398)
			(stroke
				(width 0.1524)
				(type default)
			)
			(layer "F.SilkS")
		)
		(fp_rect
			(start -0.508 0.9398)
			(end 0.508 -0.9398)
			(stroke
				(width 0)
				(type default)
			)
			(fill no)
			(layer "F.CrtYd")
		)
		(fp_rect
			(start -0.508 0.9398)
			(end 0.508 -0.9398)
			(stroke
				(width 0)
				(type default)
			)
			(fill no)
			(layer "F.Fab")
		)
		(pad "1" smd custom
			(at 0 -0.4445 90)
			(size 0.1397 0.1397)
			(layers "F.Cu" "F.Mask" "F.Paste")
			(net "P3V3_STBY_B")
			(options
				(clearance outline)
				(anchor circle)
			)
			(primitives
				(gr_poly
					(pts
						(arc
							(start -0.1778 -0.2794)
							(mid -0.249642 -0.249642)
							(end -0.2794 -0.1778)
						)
						(arc
							(start -0.2794 0.1778)
							(mid -0.249642 0.249642)
							(end -0.1778 0.2794)
						)
						(arc
							(start 0.1778 0.2794)
							(mid 0.249642 0.249642)
							(end 0.2794 0.1778)
						)
						(arc
							(start 0.2794 -0.1778)
							(mid 0.249642 -0.249642)
							(end 0.1778 -0.2794)
						)
					)
					(width 0)
					(fill yes)
				)
			)
		)
		(pad "2" smd custom
			(at 0 0.4445 90)
			(size 0.1397 0.1397)
			(layers "F.Cu" "F.Mask" "F.Paste")
			(net "IO_EXP5_A0")
			(options
				(clearance outline)
				(anchor circle)
			)
			(primitives
				(gr_poly
					(pts
						(arc
							(start -0.1778 -0.2794)
							(mid -0.249642 -0.249642)
							(end -0.2794 -0.1778)
						)
						(arc
							(start -0.2794 0.1778)
							(mid -0.249642 0.249642)
							(end -0.1778 0.2794)
						)
						(arc
							(start 0.1778 0.2794)
							(mid 0.249642 0.249642)
							(end 0.2794 0.1778)
						)
						(arc
							(start 0.2794 -0.1778)
							(mid 0.249642 -0.249642)
							(end 0.1778 -0.2794)
						)
					)
					(width 0)
					(fill yes)
				)
			)
		)
	)
	(footprint ""
		(layer "F.Cu")
		(at 332.359 -151.892 180)
		(property "Reference" "C265"
			(at 0 0 180)
			(layer "F.SilkS")
			(hide yes)
			(effects
				(font
					(size 1.27 1.27)
				)
			)
		)
		(property "Value" "SC10U16V6KX-2GP"
			(at -0.0762 -5.1308 180)
			(unlocked yes)
			(layer "F.Fab")
			(hide yes)
			(effects
				(font
					(size 1.016 1.016)
					(thickness 0.1524)
				)
			)
		)
		(property "Device Type" "C1206H71"
			(at -0.127 -6.6548 180)
			(unlocked yes)
			(layer "F.Fab")
			(hide yes)
			(effects
				(font
					(size 1.016 1.016)
					(thickness 0.1524)
				)
			)
		)
		(duplicate_pad_numbers_are_jumpers no)
		(fp_line
			(start 1.016 2.2352)
			(end -1.016 2.2352)
			(stroke
				(width 0.1524)
				(type default)
			)
			(layer "F.SilkS")
		)
		(fp_line
			(start 1.016 0.8382)
			(end 1.016 2.2352)
			(stroke
				(width 0.1524)
				(type default)
			)
			(layer "F.SilkS")
		)
		(fp_line
			(start 1.016 -2.2352)
			(end 1.016 -0.8382)
			(stroke
				(width 0.1524)
				(type default)
			)
			(layer "F.SilkS")
		)
		(fp_line
			(start -1.016 2.2352)
			(end -1.016 0.8382)
			(stroke
				(width 0.1524)
				(type default)
			)
			(layer "F.SilkS")
		)
		(fp_line
			(start -1.016 -0.8382)
			(end -1.016 -2.2352)
			(stroke
				(width 0.1524)
				(type default)
			)
			(layer "F.SilkS")
		)
		(fp_line
			(start -1.016 -2.2352)
			(end 1.016 -2.2352)
			(stroke
				(width 0.1524)
				(type default)
			)
			(layer "F.SilkS")
		)
		(fp_rect
			(start -1.0922 2.3114)
			(end 1.0922 -2.3114)
			(stroke
				(width 0)
				(type default)
			)
			(fill no)
			(layer "F.CrtYd")
		)
		(fp_poly
			(pts
				(xy 1.0922 -2.3114) (xy 1.0922 2.3114) (xy -1.0922 2.3114) (xy -1.0922 -2.3114)
			)
			(stroke
				(width 0)
				(type default)
			)
			(fill no)
			(layer "F.Fab")
		)
		(pad "1" smd rect
			(at 0 -1.397 180)
			(size 1.651 1.27)
			(layers "F.Cu" "F.Mask" "F.Paste")
			(net "P5V_HDD18")
		)
		(pad "2" smd rect
			(at 0 1.397 180)
			(size 1.651 1.27)
			(layers "F.Cu" "F.Mask" "F.Paste")
			(net "GND")
		)
	)
	(footprint ""
		(layer "F.Cu")
		(at 396.621 -274.955 180)
		(property "Reference" "C139"
			(at 0 0 180)
			(layer "F.SilkS")
			(hide yes)
			(effects
				(font
					(size 1.27 1.27)
				)
			)
		)
		(property "Value" "SC4D7U25V5KX-1-GP"
			(at -0.0762 -6.1214 180)
			(unlocked yes)
			(layer "F.Fab")
			(hide yes)
			(effects
				(font
					(size 1.016 1.016)
					(thickness 0.1524)
				)
			)
		)
		(property "Device Type" "C805H58"
			(at -0.0762 -8.1534 180)
			(unlocked yes)
			(layer "F.Fab")
			(hide yes)
			(effects
				(font
					(size 1.016 1.016)
					(thickness 0.1524)
				)
			)
		)
		(duplicate_pad_numbers_are_jumpers no)
		(fp_line
			(start 0.635 0)
			(end -0.635 0)
			(stroke
				(width 0.508)
				(type default)
			)
			(layer "F.SilkS")
		)
		(fp_rect
			(start -0.9652 1.778)
			(end 0.9652 -1.778)
			(stroke
				(width 0)
				(type default)
			)
			(fill no)
			(layer "F.CrtYd")
		)
		(fp_poly
			(pts
				(xy -0.9652 -1.778) (xy 0.9652 -1.778) (xy 0.9652 1.778) (xy -0.9652 1.778)
			)
			(stroke
				(width 0)
				(type default)
			)
			(fill no)
			(layer "F.Fab")
		)
		(pad "1" smd rect
			(at 0 -0.9652 180)
			(size 1.397 1.143)
			(layers "F.Cu" "F.Mask" "F.Paste")
			(net "P12V_HDD8")
		)
		(pad "2" smd rect
			(at 0 0.9652 180)
			(size 1.397 1.143)
			(layers "F.Cu" "F.Mask" "F.Paste")
			(net "GND")
		)
	)
	(footprint ""
		(layer "F.Cu")
		(at 364.998 -44.958 180)
		(property "Reference" "C438"
			(at 0 0 180)
			(layer "F.SilkS")
			(hide yes)
			(effects
				(font
					(size 1.27 1.27)
				)
			)
		)
		(property "Value" "SC4D7U25V5KX-1-GP"
			(at -0.0762 -6.1214 180)
			(unlocked yes)
			(layer "F.Fab")
			(hide yes)
			(effects
				(font
					(size 1.016 1.016)
					(thickness 0.1524)
				)
			)
		)
		(property "Device Type" "C805H58"
			(at -0.0762 -8.1534 180)
			(unlocked yes)
			(layer "F.Fab")
			(hide yes)
			(effects
				(font
					(size 1.016 1.016)
					(thickness 0.1524)
				)
			)
		)
		(duplicate_pad_numbers_are_jumpers no)
		(fp_line
			(start 0.635 0)
			(end -0.635 0)
			(stroke
				(width 0.508)
				(type default)
			)
			(layer "F.SilkS")
		)
		(fp_rect
			(start -0.9652 1.778)
			(end 0.9652 -1.778)
			(stroke
				(width 0)
				(type default)
			)
			(fill no)
			(layer "F.CrtYd")
		)
		(fp_poly
			(pts
				(xy -0.9652 -1.778) (xy 0.9652 -1.778) (xy 0.9652 1.778) (xy -0.9652 1.778)
			)
			(stroke
				(width 0)
				(type default)
			)
			(fill no)
			(layer "F.Fab")
		)
		(pad "1" smd rect
			(at 0 -0.9652 180)
			(size 1.397 1.143)
			(layers "F.Cu" "F.Mask" "F.Paste")
			(net "P12V_HDD31")
		)
		(pad "2" smd rect
			(at 0 0.9652 180)
			(size 1.397 1.143)
			(layers "F.Cu" "F.Mask" "F.Paste")
			(net "GND")
		)
	)
	(footprint ""
		(layer "F.Cu")
		(at 172.847 -375.412)
		(property "Reference" "R995"
			(at 0 0 0)
			(layer "F.SilkS")
			(hide yes)
			(effects
				(font
					(size 1.27 1.27)
				)
			)
		)
		(property "Value" "100KR2F-L1-GP"
			(at 0.064008 -3.993896 0)
			(unlocked yes)
			(layer "F.Fab")
			(hide yes)
			(effects
				(font
					(size 1.016 1.016)
					(thickness 0.1524)
				)
			)
		)
		(property "Device Type" "R402H16"
			(at 0.064008 -5.517896 0)
			(unlocked yes)
			(layer "F.Fab")
			(hide yes)
			(effects
				(font
					(size 1.016 1.016)
					(thickness 0.1524)
				)
			)
		)
		(duplicate_pad_numbers_are_jumpers no)
		(fp_line
			(start -0.508 -0.9398)
			(end -0.508 0.9398)
			(stroke
				(width 0.1524)
				(type default)
			)
			(layer "F.SilkS")
		)
		(fp_line
			(start 0.508 -0.9398)
			(end -0.508 -0.9398)
			(stroke
				(width 0.1524)
				(type default)
			)
			(layer "F.SilkS")
		)
		(fp_rect
			(start -0.508 0.9398)
			(end 0.508 -0.9398)
			(stroke
				(width 0)
				(type default)
			)
			(fill no)
			(layer "F.CrtYd")
		)
		(fp_rect
			(start -0.508 0.9398)
			(end 0.508 -0.9398)
			(stroke
				(width 0)
				(type default)
			)
			(fill no)
			(layer "F.Fab")
		)
		(pad "1" smd custom
			(at 0 -0.4445)
			(size 0.1397 0.1397)
			(layers "F.Cu" "F.Mask" "F.Paste")
			(net "P12V_IN")
			(options
				(clearance outline)
				(anchor circle)
			)
			(primitives
				(gr_poly
					(pts
						(arc
							(start -0.1778 -0.2794)
							(mid -0.249642 -0.249642)
							(end -0.2794 -0.1778)
						)
						(arc
							(start -0.2794 0.1778)
							(mid -0.249642 0.249642)
							(end -0.1778 0.2794)
						)
						(arc
							(start 0.1778 0.2794)
							(mid 0.249642 0.249642)
							(end 0.2794 0.1778)
						)
						(arc
							(start 0.2794 -0.1778)
							(mid 0.249642 -0.249642)
							(end 0.1778 -0.2794)
						)
					)
					(width 0)
					(fill yes)
				)
			)
		)
		(pad "2" smd custom
			(at 0 0.4445)
			(size 0.1397 0.1397)
			(layers "F.Cu" "F.Mask" "F.Paste")
			(net "MB0_P12V_PWGIN_R")
			(options
				(clearance outline)
				(anchor circle)
			)
			(primitives
				(gr_poly
					(pts
						(arc
							(start -0.1778 -0.2794)
							(mid -0.249642 -0.249642)
							(end -0.2794 -0.1778)
						)
						(arc
							(start -0.2794 0.1778)
							(mid -0.249642 0.249642)
							(end -0.1778 0.2794)
						)
						(arc
							(start 0.1778 0.2794)
							(mid 0.249642 0.249642)
							(end 0.2794 0.1778)
						)
						(arc
							(start 0.2794 -0.1778)
							(mid 0.249642 -0.249642)
							(end 0.1778 -0.2794)
						)
					)
					(width 0)
					(fill yes)
				)
			)
		)
	)
	(footprint ""
		(layer "F.Cu")
		(at 150.495 -45.466 180)
		(property "Reference" "C401"
			(at 0 0 180)
			(layer "F.SilkS")
			(hide yes)
			(effects
				(font
					(size 1.27 1.27)
				)
			)
		)
		(property "Value" "SC1U25V3KX-GP"
			(at 0 -2.8194 180)
			(unlocked yes)
			(layer "F.Fab")
			(hide yes)
			(effects
				(font
					(size 1.016 1.016)
					(thickness 0.1524)
				)
			)
		)
		(property "Device Type" "C603H36"
			(at 0 -4.3434 180)
			(unlocked yes)
			(layer "F.Fab")
			(hide yes)
			(effects
				(font
					(size 1.016 1.016)
					(thickness 0.1524)
				)
			)
		)
		(duplicate_pad_numbers_are_jumpers no)
		(fp_line
			(start 0.508 0)
			(end -0.508 0)
			(stroke
				(width 0.2032)
				(type default)
			)
			(layer "F.SilkS")
		)
		(fp_rect
			(start -0.5842 1.3335)
			(end 0.5842 -1.3335)
			(stroke
				(width 0)
				(type default)
			)
			(fill no)
			(layer "F.CrtYd")
		)
		(fp_rect
			(start -0.5842 1.3335)
			(end 0.5842 -1.3335)
			(stroke
				(width 0)
				(type default)
			)
			(fill no)
			(layer "F.Fab")
		)
		(pad "1" smd custom
			(at 0 -0.762 180)
			(size 0.2159 0.2159)
			(layers "F.Cu" "F.Mask" "F.Paste")
			(net "P12V_HDD28")
			(options
				(clearance outline)
				(anchor circle)
			)
			(primitives
				(gr_poly
					(pts
						(arc
							(start -0.3302 -0.4318)
							(mid -0.402042 -0.402042)
							(end -0.4318 -0.3302)
						)
						(arc
							(start -0.4318 0.3302)
							(mid -0.402042 0.402042)
							(end -0.3302 0.4318)
						)
						(arc
							(start 0.3302 0.4318)
							(mid 0.402042 0.402042)
							(end 0.4318 0.3302)
						)
						(arc
							(start 0.4318 -0.3302)
							(mid 0.402042 -0.402042)
							(end 0.3302 -0.4318)
						)
					)
					(width 0)
					(fill yes)
				)
			)
		)
		(pad "2" smd custom
			(at 0 0.762 180)
			(size 0.2159 0.2159)
			(layers "F.Cu" "F.Mask" "F.Paste")
			(net "GND")
			(options
				(clearance outline)
				(anchor circle)
			)
			(primitives
				(gr_poly
					(pts
						(arc
							(start -0.3302 -0.4318)
							(mid -0.402042 -0.402042)
							(end -0.4318 -0.3302)
						)
						(arc
							(start -0.4318 0.3302)
							(mid -0.402042 0.402042)
							(end -0.3302 0.4318)
						)
						(arc
							(start 0.3302 0.4318)
							(mid 0.402042 0.402042)
							(end 0.4318 0.3302)
						)
						(arc
							(start 0.4318 -0.3302)
							(mid 0.402042 -0.402042)
							(end 0.3302 -0.4318)
						)
					)
					(width 0)
					(fill yes)
				)
			)
		)
	)
	(footprint ""
		(layer "F.Cu")
		(at 433.324 -27.813 -90)
		(property "Reference" "R843"
			(at 0 0 270)
			(layer "F.SilkS")
			(hide yes)
			(effects
				(font
					(size 1.27 1.27)
				)
			)
		)
		(property "Value" "300KR2F-GP"
			(at 0.064008 -3.993896 270)
			(unlocked yes)
			(layer "F.Fab")
			(hide yes)
			(effects
				(font
					(size 1.016 1.016)
					(thickness 0.1524)
				)
			)
		)
		(property "Device Type" "R402H16"
			(at 0.064008 -5.517896 270)
			(unlocked yes)
			(layer "F.Fab")
			(hide yes)
			(effects
				(font
					(size 1.016 1.016)
					(thickness 0.1524)
				)
			)
		)
		(duplicate_pad_numbers_are_jumpers no)
		(fp_line
			(start -0.508 -0.9398)
			(end -0.508 0.9398)
			(stroke
				(width 0.1524)
				(type default)
			)
			(layer "F.SilkS")
		)
		(fp_line
			(start 0.508 -0.9398)
			(end -0.508 -0.9398)
			(stroke
				(width 0.1524)
				(type default)
			)
			(layer "F.SilkS")
		)
		(fp_rect
			(start -0.508 0.9398)
			(end 0.508 -0.9398)
			(stroke
				(width 0)
				(type default)
			)
			(fill no)
			(layer "F.CrtYd")
		)
		(fp_rect
			(start -0.508 0.9398)
			(end 0.508 -0.9398)
			(stroke
				(width 0)
				(type default)
			)
			(fill no)
			(layer "F.Fab")
		)
		(pad "1" smd custom
			(at 0 -0.4445 270)
			(size 0.1397 0.1397)
			(layers "F.Cu" "F.Mask" "F.Paste")
			(net "SW_HDD_N33")
			(options
				(clearance outline)
				(anchor circle)
			)
			(primitives
				(gr_poly
					(pts
						(arc
							(start -0.1778 -0.2794)
							(mid -0.249642 -0.249642)
							(end -0.2794 -0.1778)
						)
						(arc
							(start -0.2794 0.1778)
							(mid -0.249642 0.249642)
							(end -0.1778 0.2794)
						)
						(arc
							(start 0.1778 0.2794)
							(mid 0.249642 0.249642)
							(end 0.2794 0.1778)
						)
						(arc
							(start 0.2794 -0.1778)
							(mid 0.249642 -0.249642)
							(end 0.1778 -0.2794)
						)
					)
					(width 0)
					(fill yes)
				)
			)
		)
		(pad "2" smd custom
			(at 0 0.4445 270)
			(size 0.1397 0.1397)
			(layers "F.Cu" "F.Mask" "F.Paste")
			(net "P12V_B")
			(options
				(clearance outline)
				(anchor circle)
			)
			(primitives
				(gr_poly
					(pts
						(arc
							(start -0.1778 -0.2794)
							(mid -0.249642 -0.249642)
							(end -0.2794 -0.1778)
						)
						(arc
							(start -0.2794 0.1778)
							(mid -0.249642 0.249642)
							(end -0.1778 0.2794)
						)
						(arc
							(start 0.1778 0.2794)
							(mid 0.249642 0.249642)
							(end 0.2794 0.1778)
						)
						(arc
							(start 0.2794 -0.1778)
							(mid 0.249642 -0.249642)
							(end 0.1778 -0.2794)
						)
					)
					(width 0)
					(fill yes)
				)
			)
		)
	)
	(footprint ""
		(layer "F.Cu")
		(at 444.407036 -99.705922 180)
		(property "Reference" "Q263"
			(at 0 0 180)
			(layer "F.SilkS")
			(hide yes)
			(effects
				(font
					(size 1.27 1.27)
				)
			)
		)
		(property "Value" "SSM3K324R-GP"
			(at 0.127 -8.9662 180)
			(unlocked yes)
			(layer "F.Fab")
			(hide yes)
			(effects
				(font
					(size 1.016 1.016)
					(thickness 0.1524)
				)
			)
		)
		(property "Device Type" "SOT23DGS2D4H35"
			(at 0.127 -10.4902 180)
			(unlocked yes)
			(layer "F.Fab")
			(hide yes)
			(effects
				(font
					(size 1.016 1.016)
					(thickness 0.1524)
				)
			)
		)
		(duplicate_pad_numbers_are_jumpers no)
		(fp_line
			(start 1.651 1.778)
			(end 1.651 -1.778)
			(stroke
				(width 0.1524)
				(type default)
			)
			(layer "F.SilkS")
		)
		(fp_line
			(start 1.651 -1.778)
			(end -1.651 -1.778)
			(stroke
				(width 0.1524)
				(type default)
			)
			(layer "F.SilkS")
		)
		(fp_line
			(start -1.651 1.778)
			(end 1.651 1.778)
			(stroke
				(width 0.1524)
				(type default)
			)
			(layer "F.SilkS")
		)
		(fp_line
			(start -1.651 -1.778)
			(end -1.651 1.778)
			(stroke
				(width 0.1524)
				(type default)
			)
			(layer "F.SilkS")
		)
		(fp_poly
			(pts
				(xy -1.778 1.8796) (xy -1.778 -1.8796) (xy 1.778 -1.8796) (xy 1.778 1.8796)
			)
			(stroke
				(width 0)
				(type default)
			)
			(fill no)
			(layer "F.CrtYd")
		)
		(fp_poly
			(pts
				(xy -1.778 1.8796) (xy -1.778 -1.8796) (xy 1.778 -1.8796) (xy 1.778 1.8796)
			)
			(stroke
				(width 0)
				(type default)
			)
			(fill no)
			(layer "F.Fab")
		)
		(pad "D" smd custom
			(at 0 -0.9525 180)
			(size 0.1905 0.1905)
			(layers "F.Cu" "F.Mask" "F.Paste")
			(net "DRV_ACT_22_N")
			(options
				(clearance outline)
				(anchor circle)
			)
			(primitives
				(gr_poly
					(pts
						(arc
							(start -0.1778 0.5715)
							(mid -0.321484 0.511984)
							(end -0.381 0.3683)
						)
						(arc
							(start -0.381 -0.3683)
							(mid -0.321484 -0.511984)
							(end -0.1778 -0.5715)
						)
						(arc
							(start 0.1778 -0.5715)
							(mid 0.321484 -0.511984)
							(end 0.381 -0.3683)
						)
						(arc
							(start 0.381 0.3683)
							(mid 0.321484 0.511984)
							(end 0.1778 0.5715)
						)
					)
					(width 0)
					(fill yes)
				)
			)
		)
		(pad "G" smd custom
			(at -0.98425 0.9525 180)
			(size 0.1905 0.1905)
			(layers "F.Cu" "F.Mask" "F.Paste")
			(net "DRIVE_B_22_ACT")
			(options
				(clearance outline)
				(anchor circle)
			)
			(primitives
				(gr_poly
					(pts
						(arc
							(start -0.1778 0.5715)
							(mid -0.321484 0.511984)
							(end -0.381 0.3683)
						)
						(arc
							(start -0.381 -0.3683)
							(mid -0.321484 -0.511984)
							(end -0.1778 -0.5715)
						)
						(arc
							(start 0.1778 -0.5715)
							(mid 0.321484 -0.511984)
							(end 0.381 -0.3683)
						)
						(arc
							(start 0.381 0.3683)
							(mid 0.321484 0.511984)
							(end 0.1778 0.5715)
						)
					)
					(width 0)
					(fill yes)
				)
			)
		)
		(pad "S" smd custom
			(at 0.98425 0.9525 180)
			(size 0.1905 0.1905)
			(layers "F.Cu" "F.Mask" "F.Paste")
			(net "GND")
			(options
				(clearance outline)
				(anchor circle)
			)
			(primitives
				(gr_poly
					(pts
						(arc
							(start -0.1778 0.5715)
							(mid -0.321484 0.511984)
							(end -0.381 0.3683)
						)
						(arc
							(start -0.381 -0.3683)
							(mid -0.321484 -0.511984)
							(end -0.1778 -0.5715)
						)
						(arc
							(start 0.1778 -0.5715)
							(mid 0.321484 -0.511984)
							(end 0.381 -0.3683)
						)
						(arc
							(start 0.381 0.3683)
							(mid 0.321484 0.511984)
							(end 0.1778 0.5715)
						)
					)
					(width 0)
					(fill yes)
				)
			)
		)
	)
)
